(kicad_pcb
	(version 20260206)
	(generator "pcbnew")
	(generator_version "10.0")
	(general
		(thickness 1.6)
		(legacy_teardrops no)
	)
	(paper "A4")
	(title_block
		(title "timecard-production-celestica-r4006 — R4006-B0001-02_R01.brd")
		(comment 1 "Time Appliance Project (Time Card) / footprints 900-905 of 1113")
	)
	(layers
		(0 "F.Cu" signal "TOP")
		(4 "In1.Cu" signal "L02_GND1")
		(6 "In2.Cu" signal "L03_SIG1")
		(8 "In3.Cu" signal "L04_GND2")
		(10 "In4.Cu" signal "L05_VCC1")
		(12 "In5.Cu" signal "L06_VCC2")
		(14 "In6.Cu" signal "L07_GND3")
		(16 "In7.Cu" signal "L08_SIG2")
		(18 "In8.Cu" signal "L09_GND4")
		(2 "B.Cu" signal "BOTTOM")
		(9 "F.Adhes" user "F.Adhesive")
		(11 "B.Adhes" user "B.Adhesive")
		(13 "F.Paste" user "Package Geometry/Pastemask Top")
		(15 "B.Paste" user "Package Geometry/Pastemask Bottom")
		(5 "F.SilkS" user "Ref Des/Silkscreen Top")
		(7 "B.SilkS" user "Ref Des/Silkscreen Bottom")
		(1 "F.Mask" user "Board Geometry/Soldermask Top")
		(3 "B.Mask" user "Board Geometry/Soldermask Bottom")
		(17 "Dwgs.User" user "User.Drawings")
		(19 "Cmts.User" user "User.Comments")
		(21 "Eco1.User" user "User.Eco1")
		(23 "Eco2.User" user "User.Eco2")
		(25 "Edge.Cuts" user "Board Geometry/Outline")
		(27 "Margin" user)
		(31 "F.CrtYd" user "Package Geometry/Place Bound Top")
		(29 "B.CrtYd" user "Package Geometry/Place Bound Bottom")
		(35 "F.Fab" user "Ref Des/Assembly Top")
		(33 "B.Fab" user "Ref Des/Assembly Bottom")
	)
	(footprint ""
		(layer "B.Cu")
		(at 101.847142 -37.323014 90)
		(property "Reference" "C124"
			(at -1.524254 -42.018712 270)
			(unlocked yes)
			(layer "B.SilkS")
			(effects
				(font
					(size 0.635 0.4064)
					(thickness 0.1524)
				)
				(justify mirror)
			)
		)
		(property "Value" "VAL*"
			(at 0 3.718306 90)
			(unlocked yes)
			(layer "B.Fab")
			(hide yes)
			(effects
				(font
					(size 0.7874 0.5842)
					(thickness 0.127)
				)
				(justify mirror)
			)
		)
		(property "Tolerance" "TOL*"
			(at 0 4.861306 90)
			(unlocked yes)
			(layer "Cmts.User")
			(hide yes)
			(effects
				(font
					(size 0.7874 0.5842)
					(thickness 0.127)
				)
				(justify mirror)
			)
		)
		(property "User Part Number" "PARTNUM*"
			(at 0 2.575306 90)
			(unlocked yes)
			(layer "Cmts.User")
			(hide yes)
			(effects
				(font
					(size 0.7874 0.5842)
					(thickness 0.127)
				)
				(justify mirror)
			)
		)
		(property "Device Type" "CAPACITOR-G105-0B104-CK,0.1UF,A"
			(at 0 1.432306 90)
			(unlocked yes)
			(layer "B.Fab")
			(hide yes)
			(effects
				(font
					(size 0.7874 0.5842)
					(thickness 0.127)
				)
				(justify mirror)
			)
		)
		(duplicate_pad_numbers_are_jumpers no)
		(fp_line
			(start 0.970026 -0.4699)
			(end -0.970026 -0.4699)
			(stroke
				(width 0.1)
				(type default)
			)
			(layer "B.SilkS")
		)
		(fp_line
			(start -0.970026 -0.4699)
			(end -0.970026 0.4699)
			(stroke
				(width 0.1)
				(type default)
			)
			(layer "B.SilkS")
		)
		(fp_line
			(start 0.970026 0.4699)
			(end 0.970026 -0.4699)
			(stroke
				(width 0.1)
				(type default)
			)
			(layer "B.SilkS")
		)
		(fp_line
			(start -0.970026 0.4699)
			(end 0.970026 0.4699)
			(stroke
				(width 0.1)
				(type default)
			)
			(layer "B.SilkS")
		)
		(fp_poly
			(pts
				(xy 0.970026 0.4699) (xy -0.970026 0.4699) (xy -0.970026 -0.4699) (xy 0.970026 -0.4699)
			)
			(stroke
				(width 0)
				(type default)
			)
			(fill no)
			(layer "B.CrtYd")
		)
		(fp_line
			(start 0.508 -0.3048)
			(end -0.508 -0.3048)
			(stroke
				(width 0.1)
				(type default)
			)
			(layer "B.Fab")
		)
		(fp_line
			(start -0.508 -0.3048)
			(end -0.508 0.3048)
			(stroke
				(width 0.1)
				(type default)
			)
			(layer "B.Fab")
		)
		(fp_line
			(start 0.508 0.3048)
			(end 0.508 -0.3048)
			(stroke
				(width 0.1)
				(type default)
			)
			(layer "B.Fab")
		)
		(fp_line
			(start -0.508 0.3048)
			(end 0.508 0.3048)
			(stroke
				(width 0.1)
				(type default)
			)
			(layer "B.Fab")
		)
		(pad "1" smd circle
			(at 0.500126 0 270)
			(size 0.635 0.635)
			(layers "B.Cu" "B.Mask" "B.Paste")
			(net "XP1R0V_FPGA_MGTAVCC")
		)
		(pad "2" smd circle
			(at -0.500126 0 270)
			(size 0.635 0.635)
			(layers "B.Cu" "B.Mask" "B.Paste")
			(net "SG")
		)
	)
	(footprint ""
		(layer "B.Cu")
		(at 151.892 -39.624 90)
		(property "Reference" "R432"
			(at -7.02437 0.635 0)
			(unlocked yes)
			(layer "B.SilkS")
			(effects
				(font
					(size 0.7874 0.5842)
					(thickness 0.1524)
				)
				(justify mirror)
			)
		)
		(property "Value" "VAL*"
			(at -0.02032 2.13233 90)
			(unlocked yes)
			(layer "B.Fab")
			(hide yes)
			(effects
				(font
					(size 0.7874 0.5842)
					(thickness 0.1524)
				)
				(justify mirror)
			)
		)
		(property "Tolerance" "TOL*"
			(at -0.044704 3.05435 90)
			(unlocked yes)
			(layer "Cmts.User")
			(hide yes)
			(effects
				(font
					(size 0.7874 0.5842)
					(thickness 0.1524)
				)
				(justify mirror)
			)
		)
		(property "User Part Number" "PARTNUM*"
			(at -0.02032 4.024884 90)
			(unlocked yes)
			(layer "Cmts.User")
			(hide yes)
			(effects
				(font
					(size 0.7874 0.5842)
					(thickness 0.1524)
				)
				(justify mirror)
			)
		)
		(property "Device Type" "RESISTOR-G155-133R0-01,33OHM,1%"
			(at -0.008382 1.210564 90)
			(unlocked yes)
			(layer "B.Fab")
			(hide yes)
			(effects
				(font
					(size 0.7874 0.5842)
					(thickness 0.1524)
				)
				(justify mirror)
			)
		)
		(duplicate_pad_numbers_are_jumpers no)
		(fp_line
			(start 1.143 -0.5588)
			(end 1.143 0.5588)
			(stroke
				(width 0.1)
				(type default)
			)
			(layer "B.SilkS")
		)
		(fp_line
			(start -1.143 -0.5588)
			(end 1.143 -0.5588)
			(stroke
				(width 0.1)
				(type default)
			)
			(layer "B.SilkS")
		)
		(fp_line
			(start 1.143 0.5588)
			(end -1.143 0.5588)
			(stroke
				(width 0.1)
				(type default)
			)
			(layer "B.SilkS")
		)
		(fp_line
			(start -1.143 0.5588)
			(end -1.143 -0.5588)
			(stroke
				(width 0.1)
				(type default)
			)
			(layer "B.SilkS")
		)
		(fp_poly
			(pts
				(xy 1.143 0.5588) (xy -1.143 0.5588) (xy -1.143 -0.5588) (xy 1.143 -0.5588)
			)
			(stroke
				(width 0)
				(type default)
			)
			(fill no)
			(layer "B.CrtYd")
		)
		(fp_line
			(start 0.508 -0.3048)
			(end 0.508 0.3048)
			(stroke
				(width 0.1)
				(type default)
			)
			(layer "B.Fab")
		)
		(fp_line
			(start -0.508 -0.3048)
			(end 0.508 -0.3048)
			(stroke
				(width 0.1)
				(type default)
			)
			(layer "B.Fab")
		)
		(fp_line
			(start 0.508 0.3048)
			(end -0.508 0.3048)
			(stroke
				(width 0.1)
				(type default)
			)
			(layer "B.Fab")
		)
		(fp_line
			(start -0.508 0.3048)
			(end -0.508 -0.3048)
			(stroke
				(width 0.1)
				(type default)
			)
			(layer "B.Fab")
		)
		(pad "1" smd rect
			(at 0.5334 0 270)
			(size 0.7112 0.6096)
			(layers "B.Cu" "B.Mask" "B.Paste")
			(net "UNNAMED_16_CONNHDR2X6FSSMT_I1_7")
		)
		(pad "2" smd rect
			(at -0.5334 0 270)
			(size 0.7112 0.6096)
			(layers "B.Cu" "B.Mask" "B.Paste")
			(net "FPGA_IO_2")
		)
		(zone
			(layer "B.Cu")
			(hatch none 0.5)
			(connect_pads
				(clearance 0)
			)
			(min_thickness 0.25)
			(keepout
				(tracks not_allowed)
				(vias allowed)
				(pads allowed)
				(copperpour not_allowed)
				(footprints allowed)
			)
			(placement
				(enabled no)
				(sheetname "")
			)
			(fill
				(thermal_gap 0.5)
				(thermal_bridge_width 0.5)
				(island_removal_mode 0)
			)
			(polygon
				(pts
					(xy 152.1968 -39.7002) (xy 151.5872 -39.7002) (xy 151.5872 -39.5478) (xy 152.1968 -39.5478)
				)
			)
		)
		(zone
			(layer "B.Cu")
			(hatch none 0.5)
			(connect_pads
				(clearance 0)
			)
			(min_thickness 0.25)
			(keepout
				(tracks allowed)
				(vias not_allowed)
				(pads allowed)
				(copperpour not_allowed)
				(footprints allowed)
			)
			(placement
				(enabled no)
				(sheetname "")
			)
			(fill
				(thermal_gap 0.5)
				(thermal_bridge_width 0.5)
				(island_removal_mode 0)
			)
			(polygon
				(pts
					(xy 152.1968 -39.7002) (xy 151.5872 -39.7002) (xy 151.5872 -39.5478) (xy 152.1968 -39.5478)
				)
			)
		)
	)
	(footprint ""
		(layer "B.Cu")
		(at 120.347232 -50.823114 180)
		(property "Reference" "C103"
			(at -0.175768 0.961136 0)
			(unlocked yes)
			(layer "B.SilkS")
			(effects
				(font
					(size 0.635 0.4064)
					(thickness 0.1524)
				)
				(justify mirror)
			)
		)
		(property "Value" "VAL*"
			(at 0 3.718306 180)
			(unlocked yes)
			(layer "B.Fab")
			(hide yes)
			(effects
				(font
					(size 0.7874 0.5842)
					(thickness 0.127)
				)
				(justify mirror)
			)
		)
		(property "Tolerance" "TOL*"
			(at 0 4.861306 180)
			(unlocked yes)
			(layer "Cmts.User")
			(hide yes)
			(effects
				(font
					(size 0.7874 0.5842)
					(thickness 0.127)
				)
				(justify mirror)
			)
		)
		(property "User Part Number" "PARTNUM*"
			(at 0 2.575306 180)
			(unlocked yes)
			(layer "Cmts.User")
			(hide yes)
			(effects
				(font
					(size 0.7874 0.5842)
					(thickness 0.127)
				)
				(justify mirror)
			)
		)
		(property "Device Type" "CAPACITOR-G105-0B104-CK,0.1UF,A"
			(at 0 1.432306 180)
			(unlocked yes)
			(layer "B.Fab")
			(hide yes)
			(effects
				(font
					(size 0.7874 0.5842)
					(thickness 0.127)
				)
				(justify mirror)
			)
		)
		(duplicate_pad_numbers_are_jumpers no)
		(fp_line
			(start 0.970026 0.4699)
			(end 0.970026 -0.4699)
			(stroke
				(width 0.1)
				(type default)
			)
			(layer "B.SilkS")
		)
		(fp_line
			(start 0.970026 -0.4699)
			(end -0.970026 -0.4699)
			(stroke
				(width 0.1)
				(type default)
			)
			(layer "B.SilkS")
		)
		(fp_line
			(start -0.970026 0.4699)
			(end 0.970026 0.4699)
			(stroke
				(width 0.1)
				(type default)
			)
			(layer "B.SilkS")
		)
		(fp_line
			(start -0.970026 -0.4699)
			(end -0.970026 0.4699)
			(stroke
				(width 0.1)
				(type default)
			)
			(layer "B.SilkS")
		)
		(fp_poly
			(pts
				(xy 0.970026 0.4699) (xy -0.970026 0.4699) (xy -0.970026 -0.4699) (xy 0.970026 -0.4699)
			)
			(stroke
				(width 0)
				(type default)
			)
			(fill no)
			(layer "B.CrtYd")
		)
		(fp_line
			(start 0.508 0.3048)
			(end 0.508 -0.3048)
			(stroke
				(width 0.1)
				(type default)
			)
			(layer "B.Fab")
		)
		(fp_line
			(start 0.508 -0.3048)
			(end -0.508 -0.3048)
			(stroke
				(width 0.1)
				(type default)
			)
			(layer "B.Fab")
		)
		(fp_line
			(start -0.508 0.3048)
			(end 0.508 0.3048)
			(stroke
				(width 0.1)
				(type default)
			)
			(layer "B.Fab")
		)
		(fp_line
			(start -0.508 -0.3048)
			(end -0.508 0.3048)
			(stroke
				(width 0.1)
				(type default)
			)
			(layer "B.Fab")
		)
		(pad "1" smd circle
			(at 0.500126 0)
			(size 0.635 0.635)
			(layers "B.Cu" "B.Mask" "B.Paste")
			(net "XP3R3V_FPGA")
		)
		(pad "2" smd circle
			(at -0.500126 0)
			(size 0.635 0.635)
			(layers "B.Cu" "B.Mask" "B.Paste")
			(net "SG")
		)
	)
	(footprint ""
		(layer "B.Cu")
		(at 141.1478 -18.4404 90)
		(property "Reference" "R232"
			(at 6.4516 -0.21717 270)
			(unlocked yes)
			(layer "B.SilkS")
			(effects
				(font
					(size 0.7874 0.5842)
					(thickness 0.1524)
				)
				(justify mirror)
			)
		)
		(property "Value" "VAL*"
			(at -0.0508 2.245106 90)
			(unlocked yes)
			(layer "B.Fab")
			(hide yes)
			(effects
				(font
					(size 0.7874 0.5842)
					(thickness 0.1524)
				)
				(justify mirror)
			)
		)
		(property "Tolerance" "TOL*"
			(at -0.0508 3.261106 90)
			(unlocked yes)
			(layer "Cmts.User")
			(hide yes)
			(effects
				(font
					(size 0.7874 0.5842)
					(thickness 0.1524)
				)
				(justify mirror)
			)
		)
		(property "Device Type" "RESISTOR-G155-02101-01,2.1KOHMA"
			(at -0.0762 1.254506 90)
			(unlocked yes)
			(layer "B.Fab")
			(hide yes)
			(effects
				(font
					(size 0.7874 0.5842)
					(thickness 0.1524)
				)
				(justify mirror)
			)
		)
		(property "User Part Number" "PARTNUM*"
			(at -0.0762 4.302506 90)
			(unlocked yes)
			(layer "Cmts.User")
			(hide yes)
			(effects
				(font
					(size 0.7874 0.5842)
					(thickness 0.1524)
				)
				(justify mirror)
			)
		)
		(duplicate_pad_numbers_are_jumpers no)
		(fp_line
			(start 1.143 -0.5588)
			(end 1.143 0.5588)
			(stroke
				(width 0.1)
				(type default)
			)
			(layer "B.SilkS")
		)
		(fp_line
			(start -1.143 -0.5588)
			(end 1.143 -0.5588)
			(stroke
				(width 0.1)
				(type default)
			)
			(layer "B.SilkS")
		)
		(fp_line
			(start 1.143 0.5588)
			(end -1.143 0.5588)
			(stroke
				(width 0.1)
				(type default)
			)
			(layer "B.SilkS")
		)
		(fp_line
			(start -1.143 0.5588)
			(end -1.143 -0.5588)
			(stroke
				(width 0.1)
				(type default)
			)
			(layer "B.SilkS")
		)
		(fp_rect
			(start 1.143 0.5588)
			(end -1.143 -0.5588)
			(stroke
				(width 0)
				(type default)
			)
			(fill no)
			(layer "B.CrtYd")
		)
		(fp_line
			(start 0.508 -0.3048)
			(end 0.508 0.3048)
			(stroke
				(width 0.1)
				(type default)
			)
			(layer "B.Fab")
		)
		(fp_line
			(start -0.508 -0.3048)
			(end 0.508 -0.3048)
			(stroke
				(width 0.1)
				(type default)
			)
			(layer "B.Fab")
		)
		(fp_line
			(start 0.508 0.3048)
			(end -0.508 0.3048)
			(stroke
				(width 0.1)
				(type default)
			)
			(layer "B.Fab")
		)
		(fp_line
			(start -0.508 0.3048)
			(end -0.508 -0.3048)
			(stroke
				(width 0.1)
				(type default)
			)
			(layer "B.Fab")
		)
		(pad "1" smd rect
			(at 0.5334 0 270)
			(size 0.7112 0.6096)
			(layers "B.Cu" "B.Mask" "B.Paste")
			(net "SG")
		)
		(pad "2" smd rect
			(at -0.5334 0 270)
			(size 0.7112 0.6096)
			(layers "B.Cu" "B.Mask" "B.Paste")
			(net "UNNAMED_515_ISL80101IRAJZDFN10_")
		)
		(zone
			(layer "B.Cu")
			(hatch none 0.5)
			(connect_pads
				(clearance 0)
			)
			(min_thickness 0.25)
			(keepout
				(tracks allowed)
				(vias not_allowed)
				(pads allowed)
				(copperpour not_allowed)
				(footprints allowed)
			)
			(placement
				(enabled no)
				(sheetname "")
			)
			(fill
				(thermal_gap 0.5)
				(thermal_bridge_width 0.5)
				(island_removal_mode 0)
			)
			(polygon
				(pts
					(xy 141.4526 -18.5166) (xy 140.843 -18.5166) (xy 140.843 -18.3642) (xy 141.4526 -18.3642)
				)
			)
		)
	)
	(footprint ""
		(layer "B.Cu")
		(at 106.847132 -41.323006 90)
		(property "Reference" "C120"
			(at -1.015746 -41.382442 270)
			(unlocked yes)
			(layer "B.SilkS")
			(effects
				(font
					(size 0.635 0.4064)
					(thickness 0.1524)
				)
				(justify mirror)
			)
		)
		(property "Value" "VAL*"
			(at 0 3.718306 90)
			(unlocked yes)
			(layer "B.Fab")
			(hide yes)
			(effects
				(font
					(size 0.7874 0.5842)
					(thickness 0.127)
				)
				(justify mirror)
			)
		)
		(property "Device Type" "CAPACITOR-G105-0F475-BM,4.7UF,A"
			(at 0 1.432306 90)
			(unlocked yes)
			(layer "B.Fab")
			(hide yes)
			(effects
				(font
					(size 0.7874 0.5842)
					(thickness 0.127)
				)
				(justify mirror)
			)
		)
		(property "User Part Number" "PARTNUM*"
			(at 0 2.575306 90)
			(unlocked yes)
			(layer "Cmts.User")
			(hide yes)
			(effects
				(font
					(size 0.7874 0.5842)
					(thickness 0.127)
				)
				(justify mirror)
			)
		)
		(property "Tolerance" "TOL*"
			(at 0 4.861306 90)
			(unlocked yes)
			(layer "Cmts.User")
			(hide yes)
			(effects
				(font
					(size 0.7874 0.5842)
					(thickness 0.127)
				)
				(justify mirror)
			)
		)
		(duplicate_pad_numbers_are_jumpers no)
		(fp_line
			(start 0.970026 -0.4699)
			(end -0.970026 -0.4699)
			(stroke
				(width 0.1)
				(type default)
			)
			(layer "B.SilkS")
		)
		(fp_line
			(start -0.970026 -0.4699)
			(end -0.970026 0.4699)
			(stroke
				(width 0.1)
				(type default)
			)
			(layer "B.SilkS")
		)
		(fp_line
			(start 0.970026 0.4699)
			(end 0.970026 -0.4699)
			(stroke
				(width 0.1)
				(type default)
			)
			(layer "B.SilkS")
		)
		(fp_line
			(start -0.970026 0.4699)
			(end 0.970026 0.4699)
			(stroke
				(width 0.1)
				(type default)
			)
			(layer "B.SilkS")
		)
		(fp_poly
			(pts
				(xy 0.970026 0.4699) (xy -0.970026 0.4699) (xy -0.970026 -0.4699) (xy 0.970026 -0.4699)
			)
			(stroke
				(width 0)
				(type default)
			)
			(fill no)
			(layer "B.CrtYd")
		)
		(fp_line
			(start 0.508 -0.3048)
			(end -0.508 -0.3048)
			(stroke
				(width 0.1)
				(type default)
			)
			(layer "B.Fab")
		)
		(fp_line
			(start -0.508 -0.3048)
			(end -0.508 0.3048)
			(stroke
				(width 0.1)
				(type default)
			)
			(layer "B.Fab")
		)
		(fp_line
			(start 0.508 0.3048)
			(end 0.508 -0.3048)
			(stroke
				(width 0.1)
				(type default)
			)
			(layer "B.Fab")
		)
		(fp_line
			(start -0.508 0.3048)
			(end 0.508 0.3048)
			(stroke
				(width 0.1)
				(type default)
			)
			(layer "B.Fab")
		)
		(pad "1" smd circle
			(at 0.500126 0 270)
			(size 0.635 0.635)
			(layers "B.Cu" "B.Mask" "B.Paste")
			(net "XP1R8V_FPGA_VCCAUX")
		)
		(pad "2" smd circle
			(at -0.500126 0 270)
			(size 0.635 0.635)
			(layers "B.Cu" "B.Mask" "B.Paste")
			(net "SG")
		)
	)
	(footprint ""
		(layer "B.Cu")
		(at 118.347236 -45.823124 180)
		(property "Reference" "C139"
			(at -2.302764 -1.277874 0)
			(unlocked yes)
			(layer "B.SilkS")
			(effects
				(font
					(size 0.635 0.4064)
					(thickness 0.1524)
				)
				(justify mirror)
			)
		)
		(property "Value" "VAL*"
			(at 0 3.718306 180)
			(unlocked yes)
			(layer "B.Fab")
			(hide yes)
			(effects
				(font
					(size 0.7874 0.5842)
					(thickness 0.127)
				)
				(justify mirror)
			)
		)
		(property "Tolerance" "TOL*"
			(at 0 4.861306 180)
			(unlocked yes)
			(layer "Cmts.User")
			(hide yes)
			(effects
				(font
					(size 0.7874 0.5842)
					(thickness 0.127)
				)
				(justify mirror)
			)
		)
		(property "User Part Number" "PARTNUM*"
			(at 0 2.575306 180)
			(unlocked yes)
			(layer "Cmts.User")
			(hide yes)
			(effects
				(font
					(size 0.7874 0.5842)
					(thickness 0.127)
				)
				(justify mirror)
			)
		)
		(property "Device Type" "CAPACITOR-G105-0B104-CK,0.1UF,A"
			(at 0 1.432306 180)
			(unlocked yes)
			(layer "B.Fab")
			(hide yes)
			(effects
				(font
					(size 0.7874 0.5842)
					(thickness 0.127)
				)
				(justify mirror)
			)
		)
		(duplicate_pad_numbers_are_jumpers no)
		(fp_line
			(start 0.970026 0.4699)
			(end 0.970026 -0.4699)
			(stroke
				(width 0.1)
				(type default)
			)
			(layer "B.SilkS")
		)
		(fp_line
			(start 0.970026 -0.4699)
			(end -0.970026 -0.4699)
			(stroke
				(width 0.1)
				(type default)
			)
			(layer "B.SilkS")
		)
		(fp_line
			(start -0.970026 0.4699)
			(end 0.970026 0.4699)
			(stroke
				(width 0.1)
				(type default)
			)
			(layer "B.SilkS")
		)
		(fp_line
			(start -0.970026 -0.4699)
			(end -0.970026 0.4699)
			(stroke
				(width 0.1)
				(type default)
			)
			(layer "B.SilkS")
		)
		(fp_poly
			(pts
				(xy 0.970026 0.4699) (xy -0.970026 0.4699) (xy -0.970026 -0.4699) (xy 0.970026 -0.4699)
			)
			(stroke
				(width 0)
				(type default)
			)
			(fill no)
			(layer "B.CrtYd")
		)
		(fp_line
			(start 0.508 0.3048)
			(end 0.508 -0.3048)
			(stroke
				(width 0.1)
				(type default)
			)
			(layer "B.Fab")
		)
		(fp_line
			(start 0.508 -0.3048)
			(end -0.508 -0.3048)
			(stroke
				(width 0.1)
				(type default)
			)
			(layer "B.Fab")
		)
		(fp_line
			(start -0.508 0.3048)
			(end 0.508 0.3048)
			(stroke
				(width 0.1)
				(type default)
			)
			(layer "B.Fab")
		)
		(fp_line
			(start -0.508 -0.3048)
			(end -0.508 0.3048)
			(stroke
				(width 0.1)
				(type default)
			)
			(layer "B.Fab")
		)
		(pad "1" smd circle
			(at 0.500126 0)
			(size 0.635 0.635)
			(layers "B.Cu" "B.Mask" "B.Paste")
			(net "XP3R3V_FPGA")
		)
		(pad "2" smd circle
			(at -0.500126 0)
			(size 0.635 0.635)
			(layers "B.Cu" "B.Mask" "B.Paste")
			(net "SG")
		)
	)
)
